(kicad_pcb
	(version 20241229)
	(generator "pcbnew")
	(generator_version "9.0")
	(general
		(thickness 1.61)
		(legacy_teardrops no)
	)
	(paper "A3")
	(title_block
		(title "SO-DIMM DDR5 Tester")
		(date "2025-11-26")
		(rev "1.3.0")
		(comment 9 "footprints 580-586 of 627")
	)
	(layers
		(0 "F.Cu" signal)
		(4 "In1.Cu" power)
		(6 "In2.Cu" mixed)
		(8 "In3.Cu" power)
		(10 "In4.Cu" mixed)
		(12 "In5.Cu" power)
		(14 "In6.Cu" mixed)
		(16 "In7.Cu" power)
		(18 "In8.Cu" power)
		(20 "In9.Cu" mixed)
		(22 "In10.Cu" power)
		(2 "B.Cu" signal)
		(9 "F.Adhes" user "F.Adhesive")
		(11 "B.Adhes" user "B.Adhesive")
		(13 "F.Paste" user)
		(15 "B.Paste" user)
		(5 "F.SilkS" user "F.Silkscreen")
		(7 "B.SilkS" user "B.Silkscreen")
		(1 "F.Mask" user)
		(3 "B.Mask" user)
		(17 "Dwgs.User" user "User.Drawings")
		(19 "Cmts.User" user "User.Comments")
		(21 "Eco1.User" user "User.Eco1")
		(23 "Eco2.User" user "User.Eco2")
		(25 "Edge.Cuts" user)
		(27 "Margin" user)
		(31 "F.CrtYd" user "F.Courtyard")
		(29 "B.CrtYd" user "B.Courtyard")
		(35 "F.Fab" user)
		(33 "B.Fab" user)
	)
	(footprint "antmicro-footprints:C_0402_1005Metric"
		(layer "B.Cu")
		(at 144.375001 177.8025 -90)
		(descr "Capacitor SMD 0402 (1005 Metric), square (rectangular) end terminal, IPC_7351 nominal, (Body size source: IPC-SM-782 page 76, https://www.pcb-3d.com/wordpress/wp-content/uploads/ipc-sm-782a_amendment_1_and_2.pdf)")
		(tags "capacitor 0402")
		(property "Reference" "C90"
			(at 0 1.17 90)
			(layer "B.SilkS")
			(hide yes)
			(effects
				(font
					(size 0.7 0.7)
					(thickness 0.15)
				)
				(justify left bottom mirror)
			)
		)
		(property "Value" "C_100n_0402"
			(at 0 -1.169 90)
			(layer "B.Fab")
			(effects
				(font
					(size 0.7 0.7)
					(thickness 0.15)
				)
				(justify left bottom mirror)
			)
		)
		(property "Datasheet" "https://www.murata.com/products/productdetail?partno=GRM155R61H104KE14%23"
			(at 0 0 270)
			(layer "F.Fab")
			(hide yes)
			(effects
				(font
					(size 1.27 1.27)
					(thickness 0.15)
				)
			)
		)
		(property "Author" "Antmicro"
			(at -33.427499 322.177501 0)
			(layer "B.Fab")
			(hide yes)
			(effects
				(font
					(size 1 1)
					(thickness 0.15)
				)
				(justify mirror)
			)
		)
		(property "Dielectric" "X5R"
			(at -33.427499 322.177501 0)
			(layer "B.Fab")
			(hide yes)
			(effects
				(font
					(size 1 1)
					(thickness 0.15)
				)
				(justify mirror)
			)
		)
		(property "License" "Apache-2.0"
			(at -33.427499 322.177501 0)
			(layer "B.Fab")
			(hide yes)
			(effects
				(font
					(size 1 1)
					(thickness 0.15)
				)
				(justify mirror)
			)
		)
		(property "MPN" "GRM155R61H104KE14D"
			(at -33.427499 322.177501 0)
			(layer "B.Fab")
			(hide yes)
			(effects
				(font
					(size 1 1)
					(thickness 0.15)
				)
				(justify mirror)
			)
		)
		(property "Manufacturer" "Murata"
			(at -33.427499 322.177501 0)
			(layer "B.Fab")
			(hide yes)
			(effects
				(font
					(size 1 1)
					(thickness 0.15)
				)
				(justify mirror)
			)
		)
		(property "Val" "100n"
			(at -33.427499 322.177501 0)
			(layer "B.Fab")
			(hide yes)
			(effects
				(font
					(size 1 1)
					(thickness 0.15)
				)
				(justify mirror)
			)
		)
		(property "Voltage" "50V"
			(at -33.427499 322.177501 0)
			(layer "B.Fab")
			(hide yes)
			(effects
				(font
					(size 1 1)
					(thickness 0.15)
				)
				(justify mirror)
			)
		)
		(sheetname "/FPGA power/")
		(sheetfile "fpga-power.kicad_sch")
		(attr smd)
		(fp_rect
			(start -0.9656 0.4572)
			(end 0.9652 -0.4828)
			(stroke
				(width 0.05)
				(type solid)
			)
			(fill no)
			(layer "B.CrtYd")
		)
		(fp_line
			(start -0.5 0.25)
			(end 0.498 0.25)
			(stroke
				(width 0.15)
				(type solid)
			)
			(layer "B.Fab")
		)
		(fp_line
			(start 0.498 0.25)
			(end 0.498 -0.248)
			(stroke
				(width 0.15)
				(type solid)
			)
			(layer "B.Fab")
		)
		(fp_line
			(start -0.5 -0.248)
			(end -0.5 0.25)
			(stroke
				(width 0.15)
				(type solid)
			)
			(layer "B.Fab")
		)
		(fp_line
			(start 0.498 -0.248)
			(end -0.5 -0.248)
			(stroke
				(width 0.15)
				(type solid)
			)
			(layer "B.Fab")
		)
		(pad "1" smd roundrect
			(at -0.5 0 180)
			(size 0.6 0.6)
			(layers "B.Cu" "B.Mask" "B.Paste")
			(roundrect_rratio 0.25)
			(net 1 "GND")
			(pintype "passive")
		)
		(pad "2" smd roundrect
			(at 0.498 0 270)
			(size 0.6 0.6)
			(layers "B.Cu" "B.Mask" "B.Paste")
			(roundrect_rratio 0.25)
			(net 227 "+1V0")
			(pintype "passive")
		)
	)
	(footprint "antmicro-footprints:TP_SMD_1mm"
		(layer "B.Cu")
		(at 168.7 190.5 180)
		(property "Reference" "TP57"
			(at -3.4 -0.9 0)
			(layer "B.SilkS")
			(effects
				(font
					(size 0.7 0.7)
					(thickness 0.15)
				)
				(justify left bottom mirror)
			)
		)
		(property "Value" "TP_1mm_SMD"
			(at 0 -1.4 0)
			(layer "B.Fab")
			(effects
				(font
					(size 0.7 0.7)
					(thickness 0.15)
				)
				(justify left bottom mirror)
			)
		)
		(property "MPN" ""
			(at 0 0 0)
			(unlocked yes)
			(layer "B.Fab")
			(hide yes)
			(effects
				(font
					(size 1 1)
					(thickness 0.15)
				)
				(justify mirror)
			)
		)
		(property "Manufacturer" ""
			(at 0 0 0)
			(unlocked yes)
			(layer "B.Fab")
			(hide yes)
			(effects
				(font
					(size 1 1)
					(thickness 0.15)
				)
				(justify mirror)
			)
		)
		(property "Author" "Antmicro"
			(at 0 0 0)
			(unlocked yes)
			(layer "B.Fab")
			(hide yes)
			(effects
				(font
					(size 1 1)
					(thickness 0.15)
				)
				(justify mirror)
			)
		)
		(property "License" "Apache-2.0"
			(at 0 0 0)
			(unlocked yes)
			(layer "B.Fab")
			(hide yes)
			(effects
				(font
					(size 1 1)
					(thickness 0.15)
				)
				(justify mirror)
			)
		)
		(sheetname "/Supply/")
		(sheetfile "supply.kicad_sch")
		(attr exclude_from_pos_files)
		(fp_circle
			(center 0 0)
			(end 0.6 0)
			(stroke
				(width 0.05)
				(type default)
			)
			(fill no)
			(layer "B.CrtYd")
		)
		(fp_text user "License: Apache-2.0"
			(at -0.5 -5.2 0)
			(layer "B.Fab")
			(effects
				(font
					(size 0.7 0.7)
					(thickness 0.15)
				)
				(justify left bottom mirror)
			)
		)
		(fp_text user "${REFERENCE}"
			(at -0.5 -2.8 0)
			(layer "B.Fab")
			(effects
				(font
					(size 0.7 0.7)
					(thickness 0.15)
				)
				(justify left bottom mirror)
			)
		)
		(fp_text user "Author: Antmicro"
			(at -0.5 -4 0)
			(layer "B.Fab")
			(effects
				(font
					(size 0.7 0.7)
					(thickness 0.15)
				)
				(justify left bottom mirror)
			)
		)
		(pad "1" smd circle
			(at 0 0 180)
			(size 1 1)
			(layers "B.Cu" "B.Mask")
			(net 78 "/Supply/1V0_REG")
			(pinfunction "1")
			(pintype "passive")
		)
	)
	(footprint "antmicro-footprints:C_0603_1608Metric"
		(layer "B.Cu")
		(at 144.775501 174.801 180)
		(descr "Capacitor SMD 0603")
		(tags "capacitor 0603")
		(property "Reference" "C27"
			(at 0 0.9 0)
			(layer "B.SilkS")
			(hide yes)
			(effects
				(font
					(size 0.7 0.7)
					(thickness 0.15)
				)
				(justify left bottom mirror)
			)
		)
		(property "Value" "C_47u_0603"
			(at 0 -1.6 0)
			(layer "B.Fab")
			(effects
				(font
					(size 0.7 0.7)
					(thickness 0.15)
				)
				(justify left bottom mirror)
			)
		)
		(property "Datasheet" "https://www.murata.com/products/productdetail?partno=GRM188R60J476ME15%23"
			(at 0 0 180)
			(layer "F.Fab")
			(hide yes)
			(effects
				(font
					(size 1.27 1.27)
					(thickness 0.15)
				)
			)
		)
		(property "Author" "Antmicro"
			(at 289.551002 349.602 0)
			(layer "B.Fab")
			(hide yes)
			(effects
				(font
					(size 1 1)
					(thickness 0.15)
				)
				(justify mirror)
			)
		)
		(property "Dielectric" ""
			(at 289.551002 349.602 0)
			(layer "B.Fab")
			(hide yes)
			(effects
				(font
					(size 1 1)
					(thickness 0.15)
				)
				(justify mirror)
			)
		)
		(property "License" "Apache-2.0"
			(at 289.551002 349.602 0)
			(layer "B.Fab")
			(hide yes)
			(effects
				(font
					(size 1 1)
					(thickness 0.15)
				)
				(justify mirror)
			)
		)
		(property "MPN" "GRM188R60J476ME15D"
			(at 289.551002 349.602 0)
			(layer "B.Fab")
			(hide yes)
			(effects
				(font
					(size 1 1)
					(thickness 0.15)
				)
				(justify mirror)
			)
		)
		(property "Manufacturer" "Murata"
			(at 289.551002 349.602 0)
			(layer "B.Fab")
			(hide yes)
			(effects
				(font
					(size 1 1)
					(thickness 0.15)
				)
				(justify mirror)
			)
		)
		(property "Val" "47u"
			(at 289.551002 349.602 0)
			(layer "B.Fab")
			(hide yes)
			(effects
				(font
					(size 1 1)
					(thickness 0.15)
				)
				(justify mirror)
			)
		)
		(property "Voltage" ""
			(at 289.551002 349.602 0)
			(layer "B.Fab")
			(hide yes)
			(effects
				(font
					(size 1 1)
					(thickness 0.15)
				)
				(justify mirror)
			)
		)
		(sheetname "/FPGA power/")
		(sheetfile "fpga-power.kicad_sch")
		(attr smd)
		(fp_line
			(start -0.3 0.3)
			(end 0.3 0.3)
			(stroke
				(width 0.15)
				(type solid)
			)
			(layer "B.SilkS")
		)
		(fp_line
			(start -0.3 -0.3)
			(end 0.3 -0.3)
			(stroke
				(width 0.15)
				(type solid)
			)
			(layer "B.SilkS")
		)
		(fp_rect
			(start -1.24 0.7)
			(end 1.24 -0.7)
			(stroke
				(width 0.05)
				(type solid)
			)
			(fill no)
			(layer "B.CrtYd")
		)
		(fp_rect
			(start -0.8 0.4)
			(end 0.8 -0.4)
			(stroke
				(width 0.15)
				(type solid)
			)
			(fill no)
			(layer "B.Fab")
		)
		(pad "1" smd roundrect
			(at -0.7 0 180)
			(size 0.6 0.8)
			(layers "B.Cu" "B.Mask" "B.Paste")
			(roundrect_rratio 0.2)
			(net 188 "+1V8")
			(pintype "passive")
		)
		(pad "2" smd roundrect
			(at 0.7 0 180)
			(size 0.6 0.8)
			(layers "B.Cu" "B.Mask" "B.Paste")
			(roundrect_rratio 0.2)
			(net 1 "GND")
			(pintype "passive")
		)
	)
	(footprint "antmicro-footprints:Fiducial_1mm_Mask2mm"
		(layer "B.Cu")
		(at 199 114)
		(descr "Circular Fiducial, 1mm bare copper, 3mm soldermask opening")
		(tags "fiducial")
		(property "Reference" "FID1003"
			(at 0 1.4 0)
			(layer "B.SilkS")
			(hide yes)
			(effects
				(font
					(size 0.7 0.7)
					(thickness 0.15)
				)
				(justify right bottom mirror)
			)
		)
		(property "Value" "Fiducial_1mm_Mask2mm"
			(at 0 -2.2 0)
			(layer "B.Fab")
			(effects
				(font
					(size 0.7 0.7)
					(thickness 0.15)
				)
				(justify right bottom mirror)
			)
		)
		(property "Author" "Antmicro"
			(at 0 0 0)
			(layer "B.Fab")
			(hide yes)
			(effects
				(font
					(size 1 1)
					(thickness 0.15)
				)
				(justify mirror)
			)
		)
		(property "License" "Apache-2.0"
			(at 0 0 0)
			(layer "B.Fab")
			(hide yes)
			(effects
				(font
					(size 1 1)
					(thickness 0.15)
				)
				(justify mirror)
			)
		)
		(property "MPN" ""
			(at 0 0 0)
			(layer "B.Fab")
			(hide yes)
			(effects
				(font
					(size 1 1)
					(thickness 0.15)
				)
				(justify mirror)
			)
		)
		(property "Manufacturer" ""
			(at 0 0 0)
			(layer "B.Fab")
			(hide yes)
			(effects
				(font
					(size 1 1)
					(thickness 0.15)
				)
				(justify mirror)
			)
		)
		(sheetfile "sodimm-ddr5-tester.kicad_sch")
		(attr board_only exclude_from_pos_files exclude_from_bom)
		(fp_circle
			(center 0 0)
			(end 1.24 0)
			(stroke
				(width 0.05)
				(type solid)
			)
			(fill no)
			(layer "B.CrtYd")
		)
		(fp_circle
			(center 0 0)
			(end 0.999 0)
			(stroke
				(width 0.15)
				(type solid)
			)
			(fill no)
			(layer "B.Fab")
		)
		(pad "" smd circle
			(at 0 0)
			(size 1 1)
			(layers "B.Cu" "B.Mask")
			(solder_mask_margin 0.5)
			(clearance 0.5)
		)
	)
	(footprint "antmicro-footprints:TP_SMD_1mm"
		(layer "B.Cu")
		(at 177.74 168.38 180)
		(property "Reference" "TP56"
			(at 0.47 -0.4 0)
			(layer "B.SilkS")
			(effects
				(font
					(size 0.7 0.7)
					(thickness 0.15)
				)
				(justify left bottom mirror)
			)
		)
		(property "Value" "TP_1mm_SMD"
			(at 0 -1.4 0)
			(layer "B.Fab")
			(effects
				(font
					(size 0.7 0.7)
					(thickness 0.15)
				)
				(justify left bottom mirror)
			)
		)
		(property "MPN" ""
			(at 0 0 0)
			(unlocked yes)
			(layer "B.Fab")
			(hide yes)
			(effects
				(font
					(size 1 1)
					(thickness 0.15)
				)
				(justify mirror)
			)
		)
		(property "Manufacturer" ""
			(at 0 0 0)
			(unlocked yes)
			(layer "B.Fab")
			(hide yes)
			(effects
				(font
					(size 1 1)
					(thickness 0.15)
				)
				(justify mirror)
			)
		)
		(property "Author" "Antmicro"
			(at 0 0 0)
			(unlocked yes)
			(layer "B.Fab")
			(hide yes)
			(effects
				(font
					(size 1 1)
					(thickness 0.15)
				)
				(justify mirror)
			)
		)
		(property "License" "Apache-2.0"
			(at 0 0 0)
			(unlocked yes)
			(layer "B.Fab")
			(hide yes)
			(effects
				(font
					(size 1 1)
					(thickness 0.15)
				)
				(justify mirror)
			)
		)
		(sheetname "/Supply/")
		(sheetfile "supply.kicad_sch")
		(attr exclude_from_pos_files)
		(fp_circle
			(center 0 0)
			(end 0.6 0)
			(stroke
				(width 0.05)
				(type default)
			)
			(fill no)
			(layer "B.CrtYd")
		)
		(fp_text user "${REFERENCE}"
			(at -0.5 -2.8 0)
			(layer "B.Fab")
			(effects
				(font
					(size 0.7 0.7)
					(thickness 0.15)
				)
				(justify left bottom mirror)
			)
		)
		(fp_text user "License: Apache-2.0"
			(at -0.5 -5.2 0)
			(layer "B.Fab")
			(effects
				(font
					(size 0.7 0.7)
					(thickness 0.15)
				)
				(justify left bottom mirror)
			)
		)
		(fp_text user "Author: Antmicro"
			(at -0.5 -4 0)
			(layer "B.Fab")
			(effects
				(font
					(size 0.7 0.7)
					(thickness 0.15)
				)
				(justify left bottom mirror)
			)
		)
		(pad "1" smd circle
			(at 0 0 180)
			(size 1 1)
			(layers "B.Cu" "B.Mask")
			(net 298 "/Supply/PWR_SDA_2")
			(pinfunction "1")
			(pintype "passive")
		)
	)
	(footprint "antmicro-footprints:TP_SMD_1mm"
		(layer "B.Cu")
		(at 110 171.63 180)
		(property "Reference" "TP50"
			(at -3.3 -0.3 0)
			(layer "B.SilkS")
			(effects
				(font
					(size 0.7 0.7)
					(thickness 0.15)
				)
				(justify left bottom mirror)
			)
		)
		(property "Value" "TP_1mm_SMD"
			(at 0 -1.4 0)
			(layer "B.Fab")
			(effects
				(font
					(size 0.7 0.7)
					(thickness 0.15)
				)
				(justify left bottom mirror)
			)
		)
		(property "MPN" ""
			(at 0 0 0)
			(unlocked yes)
			(layer "B.Fab")
			(hide yes)
			(effects
				(font
					(size 1 1)
					(thickness 0.15)
				)
				(justify mirror)
			)
		)
		(property "Manufacturer" ""
			(at 0 0 0)
			(unlocked yes)
			(layer "B.Fab")
			(hide yes)
			(effects
				(font
					(size 1 1)
					(thickness 0.15)
				)
				(justify mirror)
			)
		)
		(property "Author" "Antmicro"
			(at 0 0 0)
			(unlocked yes)
			(layer "B.Fab")
			(hide yes)
			(effects
				(font
					(size 1 1)
					(thickness 0.15)
				)
				(justify mirror)
			)
		)
		(property "License" "Apache-2.0"
			(at 0 0 0)
			(unlocked yes)
			(layer "B.Fab")
			(hide yes)
			(effects
				(font
					(size 1 1)
					(thickness 0.15)
				)
				(justify mirror)
			)
		)
		(sheetname "/Debug FTDI/")
		(sheetfile "debug-ftdi.kicad_sch")
		(attr exclude_from_pos_files)
		(fp_circle
			(center 0 0)
			(end 0.6 0)
			(stroke
				(width 0.05)
				(type default)
			)
			(fill no)
			(layer "B.CrtYd")
		)
		(fp_text user "${REFERENCE}"
			(at -0.5 -2.8 0)
			(layer "B.Fab")
			(effects
				(font
					(size 0.7 0.7)
					(thickness 0.15)
				)
				(justify left bottom mirror)
			)
		)
		(fp_text user "License: Apache-2.0"
			(at -0.5 -5.2 0)
			(layer "B.Fab")
			(effects
				(font
					(size 0.7 0.7)
					(thickness 0.15)
				)
				(justify left bottom mirror)
			)
		)
		(fp_text user "Author: Antmicro"
			(at -0.5 -4 0)
			(layer "B.Fab")
			(effects
				(font
					(size 0.7 0.7)
					(thickness 0.15)
				)
				(justify left bottom mirror)
			)
		)
		(pad "1" smd circle
			(at 0 0 180)
			(size 1 1)
			(layers "B.Cu" "B.Mask")
			(net 645 "/Debug FTDI/UART1.TX")
			(pinfunction "1")
			(pintype "passive")
		)
	)
	(footprint "antmicro-footprints:C_0402_1005Metric"
		(layer "B.Cu")
		(at 126.875501 162.301 180)
		(descr "Capacitor SMD 0402 (1005 Metric), square (rectangular) end terminal, IPC_7351 nominal, (Body size source: IPC-SM-782 page 76, https://www.pcb-3d.com/wordpress/wp-content/uploads/ipc-sm-782a_amendment_1_and_2.pdf)")
		(tags "capacitor 0402")
		(property "Reference" "C22"
			(at 0 1.17 0)
			(layer "B.SilkS")
			(hide yes)
			(effects
				(font
					(size 0.7 0.7)
					(thickness 0.15)
				)
				(justify left bottom mirror)
			)
		)
		(property "Value" "C_100n_0402"
			(at 0 -1.169 0)
			(layer "B.Fab")
			(effects
				(font
					(size 0.7 0.7)
					(thickness 0.15)
				)
				(justify left bottom mirror)
			)
		)
		(property "Datasheet" "https://www.murata.com/products/productdetail?partno=GRM155R61H104KE14%23"
			(at 0 0 180)
			(layer "F.Fab")
			(hide yes)
			(effects
				(font
					(size 1.27 1.27)
					(thickness 0.15)
				)
			)
		)
		(property "Author" "Antmicro"
			(at 253.751002 324.602 0)
			(layer "B.Fab")
			(hide yes)
			(effects
				(font
					(size 1 1)
					(thickness 0.15)
				)
				(justify mirror)
			)
		)
		(property "Dielectric" "X5R"
			(at 253.751002 324.602 0)
			(layer "B.Fab")
			(hide yes)
			(effects
				(font
					(size 1 1)
					(thickness 0.15)
				)
				(justify mirror)
			)
		)
		(property "License" "Apache-2.0"
			(at 253.751002 324.602 0)
			(layer "B.Fab")
			(hide yes)
			(effects
				(font
					(size 1 1)
					(thickness 0.15)
				)
				(justify mirror)
			)
		)
		(property "MPN" "GRM155R61H104KE14D"
			(at 253.751002 324.602 0)
			(layer "B.Fab")
			(hide yes)
			(effects
				(font
					(size 1 1)
					(thickness 0.15)
				)
				(justify mirror)
			)
		)
		(property "Manufacturer" "Murata"
			(at 253.751002 324.602 0)
			(layer "B.Fab")
			(hide yes)
			(effects
				(font
					(size 1 1)
					(thickness 0.15)
				)
				(justify mirror)
			)
		)
		(property "Val" "100n"
			(at 253.751002 324.602 0)
			(layer "B.Fab")
			(hide yes)
			(effects
				(font
					(size 1 1)
					(thickness 0.15)
				)
				(justify mirror)
			)
		)
		(property "Voltage" "50V"
			(at 253.751002 324.602 0)
			(layer "B.Fab")
			(hide yes)
			(effects
				(font
					(size 1 1)
					(thickness 0.15)
				)
				(justify mirror)
			)
		)
		(sheetname "/FPGA power/")
		(sheetfile "fpga-power.kicad_sch")
		(attr smd)
		(fp_rect
			(start -0.9656 0.4572)
			(end 0.9652 -0.4828)
			(stroke
				(width 0.05)
				(type solid)
			)
			(fill no)
			(layer "B.CrtYd")
		)
		(fp_line
			(start 0.498 0.25)
			(end 0.498 -0.248)
			(stroke
				(width 0.15)
				(type solid)
			)
			(layer "B.Fab")
		)
		(fp_line
			(start 0.498 -0.248)
			(end -0.5 -0.248)
			(stroke
				(width 0.15)
				(type solid)
			)
			(layer "B.Fab")
		)
		(fp_line
			(start -0.5 0.25)
			(end 0.498 0.25)
			(stroke
				(width 0.15)
				(type solid)
			)
			(layer "B.Fab")
		)
		(fp_line
			(start -0.5 -0.248)
			(end -0.5 0.25)
			(stroke
				(width 0.15)
				(type solid)
			)
			(layer "B.Fab")
		)
		(pad "1" smd roundrect
			(at -0.5 0 90)
			(size 0.6 0.6)
			(layers "B.Cu" "B.Mask" "B.Paste")
			(roundrect_rratio 0.25)
			(net 1 "GND")
			(pintype "passive")
		)
		(pad "2" smd roundrect
			(at 0.498 0 180)
			(size 0.6 0.6)
			(layers "B.Cu" "B.Mask" "B.Paste")
			(roundrect_rratio 0.25)
			(net 200 "+3V3")
			(pintype "passive")
		)
	)
)
